# S9S_MB_2U (Grand Teton) — schematic netlist excerpt (pin names and nets, part order shuffled) for the footprints in the layout excerpt that follows; sources: Cadence DE-HDL packaged netlist, KiCad conversion of 03242023_DA0F0TMBIJ0_F0T_Motherboard_J_brd_V01_OCP.brd

J37  SCONN168_ME1016810202011  IO  pkg CON_F168S2H7D_P0-6W2-95_LUH  page 153
  GND_A1  = GND
  GND_A2  = GND
  GND_A3  = GND
  GND_A4  = GND
  GND_A5  = GND
  GND_A6  = GND
  SMCLK  = SMB_OCP_SFF_3V3AUX_BUF_R_SCL
  SMDAT  = SMB_OCP_SFF_3V3AUX_BUF_R_SDA
  \smrst#\  = RST_SMB_OCP_SFF_N
  \prsnta#\  = OCP_SFF_PRSNTA_R_N
  \perst1#\  = RST_PERST1_OCP_SFF_N
  \prsntb2#\  = OCP_SFF_PRSNT2_R_N
  GND_A13  = GND
  REFCLKN1  = CLK_100M_OCP_SFF_1_DN
  REFCLKP1  = CLK_100M_OCP_SFF_1_DP
  GND_A16  = GND
  PERN0  = P5E_CPU0_PE1_RX_DN<0>
  PERP0  = P5E_CPU0_PE1_RX_DP<0>
  GND_A19  = GND
  PERN1  = P5E_CPU0_PE1_RX_DP<1>
  PERP1  = P5E_CPU0_PE1_RX_DN<1>
  GND_A22  = GND
  PERN2  = P5E_CPU0_PE1_RX_DP<2>
  PERP2  = P5E_CPU0_PE1_RX_DN<2>
  GND_A25  = GND
  PERN3  = P5E_CPU0_PE1_RX_DP<3>
  PERP3  = P5E_CPU0_PE1_RX_DN<3>
  GND_A28  = GND
  GND_A29  = GND
  PERN4  = P5E_CPU0_PE1_RX_DP<4>
  PERP4  = P5E_CPU0_PE1_RX_DN<4>
  GND_A32  = GND
  PERN5  = P5E_CPU0_PE1_RX_DP<5>
  PERP5  = P5E_CPU0_PE1_RX_DN<5>
  GND_A35  = GND
  PERN6  = P5E_CPU0_PE1_RX_DP<6>
  PERP6  = P5E_CPU0_PE1_RX_DN<6>
  GND_A38  = GND
  PERN7  = P5E_CPU0_PE1_RX_DP<7>
  PERP7  = P5E_CPU0_PE1_RX_DN<7>
  GND_A41  = GND
  \prsntb1#\  = OCP_SFF_PRSNT1_R_N
  GND_A43  = GND
  PERN8  = P5E_CPU0_PE1_RX_DP<8>
  PERP8  = P5E_CPU0_PE1_RX_DN<8>
  GND_A46  = GND
  PERN9  = P5E_CPU0_PE1_RX_DP<9>
  PERP9  = P5E_CPU0_PE1_RX_DN<9>
  GND_A49  = GND
  PERN10  = P5E_CPU0_PE1_RX_DP<10>
  PERP10  = P5E_CPU0_PE1_RX_DN<10>
  GND_A52  = GND
  PERN11  = P5E_CPU0_PE1_RX_DP<11>
  PERP11  = P5E_CPU0_PE1_RX_DN<11>
  GND_A55  = GND
  PERN12  = P5E_CPU0_PE1_RX_DP<12>
  PERP12  = P5E_CPU0_PE1_RX_DN<12>
  GND_A58  = GND
  PERN13  = P5E_CPU0_PE1_RX_DP<13>
  PERP13  = P5E_CPU0_PE1_RX_DN<13>
  GND_A61  = GND
  PERN14  = P5E_CPU0_PE1_RX_DP<14>
  PERP14  = P5E_CPU0_PE1_RX_DN<14>
  GND_A64  = GND
  PERN15  = P5E_CPU0_PE1_RX_DP<15>
  PERP15  = P5E_CPU0_PE1_RX_DN<15>
  GND_A67  = GND
  USB_DATN  = OCP_SFF_USB2_3_DN
  USB_DATP  = OCP_SFF_USB2_3_DP
  \pwrbrk0#\  = OCP_SFF_PWRBRK_N
  \+12v_edge_b1\  = P12V_OCP_SFF
  \+12v_edge_b2\  = P12V_OCP_SFF
  \+12v_edge_b3\  = P12V_OCP_SFF
  \+12v_edge_b4\  = P12V_OCP_SFF
  \+12v_edge_b5\  = P12V_OCP_SFF
  \+12v_edge_b6\  = P12V_OCP_SFF
  \bif0#\  = OCP_SFF_BIF0_R_N
  \bif1#\  = OCP_SFF_BIF1_R_N
  \bif2#\  = OCP_SFF_BIF2_R_N
  \perst0#\  = RST_PERST0_OCP_SFF_N
  \+3.3v_edge\  = P3V3_OCP_SFF
  AUX_PWR_EN  = OCP_SFF_AUX_PWR_EN_R
  GND_B13  = GND
  REFCLKN0  = CLK_100M_OCP_SFF_0_DN
  REFCLKP0  = CLK_100M_OCP_SFF_0_DP
  GND_B16  = GND
  PETN0  = P5E_CPU0_PE1_TX_C_DN<0>
  PETP0  = P5E_CPU0_PE1_TX_C_DP<0>
  GND_B19  = GND
  PETN1  = P5E_CPU0_PE1_TX_C_DN<1>
  PETP1  = P5E_CPU0_PE1_TX_C_DP<1>
  GND_B22  = GND
  PETN2  = P5E_CPU0_PE1_TX_C_DP<2>
  PETP2  = P5E_CPU0_PE1_TX_C_DN<2>
  GND_B25  = GND
  PETN3  = P5E_CPU0_PE1_TX_C_DN<3>
  PETP3  = P5E_CPU0_PE1_TX_C_DP<3>
  GND_B28  = GND
  GND_B29  = GND
  PETN4  = P5E_CPU0_PE1_TX_C_DP<4>
  PETP4  = P5E_CPU0_PE1_TX_C_DN<4>
  GND_B32  = GND
  PETN5  = P5E_CPU0_PE1_TX_C_DN<5>
  PETP5  = P5E_CPU0_PE1_TX_C_DP<5>
  GND_B35  = GND
  PETN6  = P5E_CPU0_PE1_TX_C_DP<6>
  PETP6  = P5E_CPU0_PE1_TX_C_DN<6>
  GND_B38  = GND
  PETN7  = P5E_CPU0_PE1_TX_C_DN<7>
  PETP7  = P5E_CPU0_PE1_TX_C_DP<7>
  GND_B41  = GND
  \prsntb0#\  = OCP_SFF_PRSNT0_R_N
  GND_B43  = GND
  PETN8  = P5E_CPU0_PE1_TX_C_DP<8>
  PETP8  = P5E_CPU0_PE1_TX_C_DN<8>
  GND_B46  = GND
  PETN9  = P5E_CPU0_PE1_TX_C_DN<9>
  PETP9  = P5E_CPU0_PE1_TX_C_DP<9>
  GND_B49  = GND
  PETN10  = P5E_CPU0_PE1_TX_C_DP<10>
  PETP10  = P5E_CPU0_PE1_TX_C_DN<10>
  GND_B52  = GND
  PETN11  = P5E_CPU0_PE1_TX_C_DN<11>
  PETP11  = P5E_CPU0_PE1_TX_C_DP<11>
  GND_B55  = GND
  PETN12  = P5E_CPU0_PE1_TX_C_DP<12>
  PETP12  = P5E_CPU0_PE1_TX_C_DN<12>
  GND_B58  = GND
  PETN13  = P5E_CPU0_PE1_TX_C_DN<13>
  PETP13  = P5E_CPU0_PE1_TX_C_DP<13>
  GND_B61  = GND
  PETN14  = P5E_CPU0_PE1_TX_C_DP<14>
  PETP14  = P5E_CPU0_PE1_TX_C_DN<14>
  GND_B64  = GND
  PETN15  = P5E_CPU0_PE1_TX_C_DN<15>
  PETP15  = P5E_CPU0_PE1_TX_C_DP<15>
  GND_B67  = GND
  RFU1_NC_B68  = TP_OCP_SFF_B68
  RFU1_NC_B69  = TP_OCP_SFF_B69
  \prsntb3#\  = OCP_SFF_PRSNT3_R_N
  G1  = GND
  G2  = GND
  G3  = GND
  G4  = GND
  G5  = GND
  \perst2#\  = RST_PERST2_OCP_SFF_N
  \perst3#\  = RST_PERST3_OCP_SFF_N
  \wake#\  = IRQ_LVC3_OCP_SFF_WAKE_N
  RBT_ARB_IN  = OCP_SFF_ISO1_RBT_ARB_IN
  RBT_ARB_OUT  = OCP_SFF_ISO2_RBT_ARB_OUT
  SLOT_ID1  = OCP_SFF_ID1
  RBT_TX_EN  = NCSI_OCP_SFF_TX_EN
  RBT_TXD1  = NCSI_OCP_SFF_TXD1
  RBT_TXD0  = NCSI_OCP_SFF_TXD0
  GND_OA10  = GND
  REFCLKN3  = CLK_100M_OCP_SFF_3_DN
  REFCLKP3  = CLK_100M_OCP_SFF_3_DP
  GND_OA13  = GND
  RBT_CLK_IN  = CLK_50M_NCSI_OCP_SFF_ISO
  NIC_PWR_GOOD  = FM_OCP_SFF_PWR_GOOD
  MAIN_PWR_EN  = OCP_SFF_MAIN_PWR_EN_R
  \ld#\  = SGPIO_OCP_SFF_LD_N
  DATA_IN  = SGPIO_OCP_SFF_DATAIN
  DATA_OUT  = SGPIO_OCP_SFF_DATAOUT
  CLK  = SGPIO_OCP_SFF_CLK
  SLOT_ID0  = OCP_SFF_ID0
  RBT_RXD1  = NCSI_OCP_SFF_RXD1
  RBT_RXD0  = NCSI_OCP_SFF_RXD0
  GND_OB10  = GND
  REFCLKN2  = CLK_100M_OCP_SFF_2_DN
  REFCLKP2  = CLK_100M_OCP_SFF_2_DP
  GND_OB13  = GND
  RBT_CRS_DV  = NCSI_OCP_SFF_CRS_DV

(kicad_pcb
	(version 20260206)
	(generator "pcbnew")
	(generator_version "10.0")
	(general
		(thickness 1.6)
		(legacy_teardrops no)
	)
	(paper "A4")
	(title_block
		(title "03242023_DA0F0TMBIJ0_F0T_Motherboard_J_brd_V01_OCP.brd")
		(comment 1 "Grand Teton / footprint 2414 of 6105 (J37), pads 46-89 of 175")
	)
	(layers
		(0 "F.Cu" signal "TOP")
		(4 "In1.Cu" signal "GND")
		(6 "In2.Cu" signal "IN1")
		(8 "In3.Cu" signal "GND1")
		(10 "In4.Cu" signal "IN2")
		(12 "In5.Cu" signal "GND2")
		(14 "In6.Cu" signal "IN3")
		(16 "In7.Cu" signal "GND3")
		(18 "In8.Cu" signal "VCC")
		(20 "In9.Cu" signal "VCC1")
		(22 "In10.Cu" signal "GND4")
		(24 "In11.Cu" signal "IN4")
		(26 "In12.Cu" signal "GND5")
		(28 "In13.Cu" signal "IN5")
		(30 "In14.Cu" signal "GND6")
		(32 "In15.Cu" signal "IN6")
		(34 "In16.Cu" signal "GND7")
		(2 "B.Cu" signal "BOTTOM")
		(9 "F.Adhes" user "F.Adhesive")
		(11 "B.Adhes" user "B.Adhesive")
		(13 "F.Paste" user "Package Geometry/Pastemask Top")
		(15 "B.Paste" user "Package Geometry/Pastemask Bottom")
		(5 "F.SilkS" user "Ref Des/Silkscreen Top")
		(7 "B.SilkS" user "Ref Des/Silkscreen Bottom")
		(1 "F.Mask" user "Board Geometry/Soldermask Top")
		(3 "B.Mask" user "Board Geometry/Soldermask Bottom")
		(17 "Dwgs.User" user "User.Drawings")
		(19 "Cmts.User" user "User.Comments")
		(21 "Eco1.User" user "User.Eco1")
		(23 "Eco2.User" user "User.Eco2")
		(25 "Edge.Cuts" user "Board Geometry/Outline")
		(27 "Margin" user)
		(31 "F.CrtYd" user "Package Geometry/Place Bound Top")
		(29 "B.CrtYd" user "Package Geometry/Place Bound Bottom")
		(35 "F.Fab" user "Ref Des/Assembly Top")
		(33 "B.Fab" user "Ref Des/Assembly Bottom")
	)
	(footprint ""
		(layer "F.Cu")
		(at 421.901874 -5.569966 -90)
		(property "Reference" "J37"
			(at -16.985996 31.63951 0)
			(unlocked yes)
			(layer "F.SilkS")
			(effects
				(font
					(size 0.7874 0.5842)
					(thickness 0.1524)
				)
				(justify left)
			)
		)
		(property "Value" ""
			(at 0 0 270)
			(layer "F.Fab")
			(effects
				(font
					(size 1.27 1.27)
				)
			)
		)
		(duplicate_pad_numbers_are_jumpers no)
		(pad "A44" smd rect
			(at -2.750058 15.055088 180)
			(size 0.381 1.4478)
			(layers "F.Cu" "F.Mask" "F.Paste")
			(net "P5E_CPU0_PE1_RX_DP<8>")
		)
		(pad "A45" smd rect
			(at -2.750058 15.655036 180)
			(size 0.381 1.4478)
			(layers "F.Cu" "F.Mask" "F.Paste")
			(net "P5E_CPU0_PE1_RX_DN<8>")
		)
		(pad "A46" smd rect
			(at -2.750058 16.254984 180)
			(size 0.381 1.4478)
			(layers "F.Cu" "F.Mask" "F.Paste")
			(net "GND")
		)
		(pad "A47" smd rect
			(at -2.750058 16.854932 180)
			(size 0.381 1.4478)
			(layers "F.Cu" "F.Mask" "F.Paste")
			(net "P5E_CPU0_PE1_RX_DP<9>")
		)
		(pad "A48" smd rect
			(at -2.750058 17.45488 180)
			(size 0.381 1.4478)
			(layers "F.Cu" "F.Mask" "F.Paste")
			(net "P5E_CPU0_PE1_RX_DN<9>")
		)
		(pad "A49" smd rect
			(at -2.750058 18.055082 180)
			(size 0.381 1.4478)
			(layers "F.Cu" "F.Mask" "F.Paste")
			(net "GND")
		)
		(pad "A50" smd rect
			(at -2.750058 18.65503 180)
			(size 0.381 1.4478)
			(layers "F.Cu" "F.Mask" "F.Paste")
			(net "P5E_CPU0_PE1_RX_DP<10>")
		)
		(pad "A51" smd rect
			(at -2.750058 19.254978 180)
			(size 0.381 1.4478)
			(layers "F.Cu" "F.Mask" "F.Paste")
			(net "P5E_CPU0_PE1_RX_DN<10>")
		)
		(pad "A52" smd rect
			(at -2.750058 19.854926 180)
			(size 0.381 1.4478)
			(layers "F.Cu" "F.Mask" "F.Paste")
			(net "GND")
		)
		(pad "A53" smd rect
			(at -2.750058 20.455128 180)
			(size 0.381 1.4478)
			(layers "F.Cu" "F.Mask" "F.Paste")
			(net "P5E_CPU0_PE1_RX_DP<11>")
		)
		(pad "A54" smd rect
			(at -2.750058 21.055076 180)
			(size 0.381 1.4478)
			(layers "F.Cu" "F.Mask" "F.Paste")
			(net "P5E_CPU0_PE1_RX_DN<11>")
		)
		(pad "A55" smd rect
			(at -2.750058 21.655024 180)
			(size 0.381 1.4478)
			(layers "F.Cu" "F.Mask" "F.Paste")
			(net "GND")
		)
		(pad "A56" smd rect
			(at -2.750058 22.254972 180)
			(size 0.381 1.4478)
			(layers "F.Cu" "F.Mask" "F.Paste")
			(net "P5E_CPU0_PE1_RX_DP<12>")
		)
		(pad "A57" smd rect
			(at -2.750058 22.85492 180)
			(size 0.381 1.4478)
			(layers "F.Cu" "F.Mask" "F.Paste")
			(net "P5E_CPU0_PE1_RX_DN<12>")
		)
		(pad "A58" smd rect
			(at -2.750058 23.455122 180)
			(size 0.381 1.4478)
			(layers "F.Cu" "F.Mask" "F.Paste")
			(net "GND")
		)
		(pad "A59" smd rect
			(at -2.750058 24.05507 180)
			(size 0.381 1.4478)
			(layers "F.Cu" "F.Mask" "F.Paste")
			(net "P5E_CPU0_PE1_RX_DP<13>")
		)
		(pad "A60" smd rect
			(at -2.750058 24.655018 180)
			(size 0.381 1.4478)
			(layers "F.Cu" "F.Mask" "F.Paste")
			(net "P5E_CPU0_PE1_RX_DN<13>")
		)
		(pad "A61" smd rect
			(at -2.750058 25.254966 180)
			(size 0.381 1.4478)
			(layers "F.Cu" "F.Mask" "F.Paste")
			(net "GND")
		)
		(pad "A62" smd rect
			(at -2.750058 25.854914 180)
			(size 0.381 1.4478)
			(layers "F.Cu" "F.Mask" "F.Paste")
			(net "P5E_CPU0_PE1_RX_DP<14>")
		)
		(pad "A63" smd rect
			(at -2.750058 26.455116 180)
			(size 0.381 1.4478)
			(layers "F.Cu" "F.Mask" "F.Paste")
			(net "P5E_CPU0_PE1_RX_DN<14>")
		)
		(pad "A64" smd rect
			(at -2.750058 27.055064 180)
			(size 0.381 1.4478)
			(layers "F.Cu" "F.Mask" "F.Paste")
			(net "GND")
		)
		(pad "A65" smd rect
			(at -2.750058 27.655012 180)
			(size 0.381 1.4478)
			(layers "F.Cu" "F.Mask" "F.Paste")
			(net "P5E_CPU0_PE1_RX_DP<15>")
		)
		(pad "A66" smd rect
			(at -2.750058 28.25496 180)
			(size 0.381 1.4478)
			(layers "F.Cu" "F.Mask" "F.Paste")
			(net "P5E_CPU0_PE1_RX_DN<15>")
		)
		(pad "A67" smd rect
			(at -2.750058 28.854908 180)
			(size 0.381 1.4478)
			(layers "F.Cu" "F.Mask" "F.Paste")
			(net "GND")
		)
		(pad "A68" smd rect
			(at -2.750058 29.45511 180)
			(size 0.381 1.4478)
			(layers "F.Cu" "F.Mask" "F.Paste")
			(net "OCP_SFF_USB2_3_DN")
		)
		(pad "A69" smd rect
			(at -2.750058 30.055058 180)
			(size 0.381 1.4478)
			(layers "F.Cu" "F.Mask" "F.Paste")
			(net "OCP_SFF_USB2_3_DP")
		)
		(pad "A70" smd rect
			(at -2.750058 30.655006 180)
			(size 0.381 1.4478)
			(layers "F.Cu" "F.Mask" "F.Paste")
			(net "OCP_SFF_PWRBRK_N")
		)
		(pad "B1" smd rect
			(at -5.700014 -18.465038 180)
			(size 0.381 1.4478)
			(layers "F.Cu" "F.Mask" "F.Paste")
			(net "P12V_OCP_SFF")
		)
		(pad "B2" smd rect
			(at -5.700014 -17.86509 180)
			(size 0.381 1.4478)
			(layers "F.Cu" "F.Mask" "F.Paste")
			(net "P12V_OCP_SFF")
		)
		(pad "B3" smd rect
			(at -5.700014 -17.264888 180)
			(size 0.381 1.4478)
			(layers "F.Cu" "F.Mask" "F.Paste")
			(net "P12V_OCP_SFF")
		)
		(pad "B4" smd rect
			(at -5.700014 -16.66494 180)
			(size 0.381 1.4478)
			(layers "F.Cu" "F.Mask" "F.Paste")
			(net "P12V_OCP_SFF")
		)
		(pad "B5" smd rect
			(at -5.700014 -16.064992 180)
			(size 0.381 1.4478)
			(layers "F.Cu" "F.Mask" "F.Paste")
			(net "P12V_OCP_SFF")
		)
		(pad "B6" smd rect
			(at -5.700014 -15.465044 180)
			(size 0.381 1.4478)
			(layers "F.Cu" "F.Mask" "F.Paste")
			(net "P12V_OCP_SFF")
		)
		(pad "B7" smd rect
			(at -5.700014 -14.865096 180)
			(size 0.381 1.4478)
			(layers "F.Cu" "F.Mask" "F.Paste")
			(net "OCP_SFF_BIF0_R_N")
		)
		(pad "B8" smd rect
			(at -5.700014 -14.264894 180)
			(size 0.381 1.4478)
			(layers "F.Cu" "F.Mask" "F.Paste")
			(net "OCP_SFF_BIF1_R_N")
		)
		(pad "B9" smd rect
			(at -5.700014 -13.664946 180)
			(size 0.381 1.4478)
			(layers "F.Cu" "F.Mask" "F.Paste")
			(net "OCP_SFF_BIF2_R_N")
		)
		(pad "B10" smd rect
			(at -5.700014 -13.064998 180)
			(size 0.381 1.4478)
			(layers "F.Cu" "F.Mask" "F.Paste")
			(net "RST_PERST0_OCP_SFF_N")
		)
		(pad "B11" smd rect
			(at -5.700014 -12.46505 180)
			(size 0.381 1.4478)
			(layers "F.Cu" "F.Mask" "F.Paste")
			(net "P3V3_OCP_SFF")
		)
		(pad "B12" smd rect
			(at -5.700014 -11.865102 180)
			(size 0.381 1.4478)
			(layers "F.Cu" "F.Mask" "F.Paste")
			(net "OCP_SFF_AUX_PWR_EN_R")
		)
		(pad "B13" smd rect
			(at -5.700014 -11.2649 180)
			(size 0.381 1.4478)
			(layers "F.Cu" "F.Mask" "F.Paste")
			(net "GND")
		)
		(pad "B14" smd rect
			(at -5.700014 -10.664952 180)
			(size 0.381 1.4478)
			(layers "F.Cu" "F.Mask" "F.Paste")
			(net "CLK_100M_OCP_SFF_0_DN")
		)
		(pad "B15" smd rect
			(at -5.700014 -10.065004 180)
			(size 0.381 1.4478)
			(layers "F.Cu" "F.Mask" "F.Paste")
			(net "CLK_100M_OCP_SFF_0_DP")
		)
		(pad "B16" smd rect
			(at -5.700014 -9.465056 180)
			(size 0.381 1.4478)
			(layers "F.Cu" "F.Mask" "F.Paste")
			(net "GND")
		)
		(pad "B17" smd rect
			(at -5.700014 -8.865108 180)
			(size 0.381 1.4478)
			(layers "F.Cu" "F.Mask" "F.Paste")
			(net "P5E_CPU0_PE1_TX_C_DN<0>")
		)
	)
)
